# SCM (Grand Teton) — schematic netlist excerpt (pin names and nets, part order shuffled) for the footprints in the layout excerpt that follows; sources: Cadence DE-HDL packaged netlist, KiCad conversion of 12092022_DA0F0TMDCD0_F0T_Management_Board_D_brd_V3_OCP.brd

R468  Q_RES  90.9 1% CHIP  pkg 0402LF  page 13 : A = SPI_BMC_TPM_CLK_R1 ; B = SPI_BMC_TPM_CLK
R286  Q_RES  316 1% CHIP  pkg 0402LF  page 50 : A = LED_D21_R2 ; B = LED_D21_R1

(kicad_pcb
	(version 20260206)
	(generator "pcbnew")
	(generator_version "10.0")
	(general
		(thickness 1.6)
		(legacy_teardrops no)
	)
	(paper "A4")
	(title_block
		(title "12092022_DA0F0TMDCD0_F0T_Management_Board_D_brd_V3_OCP.brd")
		(comment 1 "Grand Teton / footprints 233-234 of 1440")
	)
	(layers
		(0 "F.Cu" signal "TOP")
		(4 "In1.Cu" signal "GND")
		(6 "In2.Cu" signal "IN1")
		(8 "In3.Cu" signal "GND1")
		(10 "In4.Cu" signal "IN2")
		(12 "In5.Cu" signal "VCC")
		(14 "In6.Cu" signal "VCC1")
		(16 "In7.Cu" signal "IN3")
		(18 "In8.Cu" signal "GND2")
		(20 "In9.Cu" signal "IN4")
		(22 "In10.Cu" signal "GND3")
		(2 "B.Cu" signal "BOTTOM")
		(9 "F.Adhes" user "F.Adhesive")
		(11 "B.Adhes" user "B.Adhesive")
		(13 "F.Paste" user "Package Geometry/Pastemask Top")
		(15 "B.Paste" user "Package Geometry/Pastemask Bottom")
		(5 "F.SilkS" user "Ref Des/Silkscreen Top")
		(7 "B.SilkS" user "Ref Des/Silkscreen Bottom")
		(1 "F.Mask" user "Board Geometry/Soldermask Top")
		(3 "B.Mask" user "Board Geometry/Soldermask Bottom")
		(17 "Dwgs.User" user "User.Drawings")
		(19 "Cmts.User" user "User.Comments")
		(21 "Eco1.User" user "User.Eco1")
		(23 "Eco2.User" user "User.Eco2")
		(25 "Edge.Cuts" user "Board Geometry/Outline")
		(27 "Margin" user)
		(31 "F.CrtYd" user "Package Geometry/Place Bound Top")
		(29 "B.CrtYd" user "Package Geometry/Place Bound Bottom")
		(35 "F.Fab" user "Ref Des/Assembly Top")
		(33 "B.Fab" user "Ref Des/Assembly Bottom")
	)
	(footprint ""
		(layer "F.Cu")
		(at 54.61 -10.795 -90)
		(property "Reference" "R286"
			(at 0 0 270)
			(layer "F.SilkS")
			(hide yes)
			(effects
				(font
					(size 1.27 1.27)
				)
			)
		)
		(property "Value" ""
			(at 0 0 270)
			(layer "F.Fab")
			(effects
				(font
					(size 1.27 1.27)
				)
			)
		)
		(duplicate_pad_numbers_are_jumpers no)
		(fp_line
			(start -0.7874 0.4064)
			(end -0.7874 -0.4064)
			(stroke
				(width 0.1524)
				(type default)
			)
			(layer "F.SilkS")
		)
		(fp_line
			(start 0.7874 0.4064)
			(end -0.7874 0.4064)
			(stroke
				(width 0.1524)
				(type default)
			)
			(layer "F.SilkS")
		)
		(fp_line
			(start -0.7874 -0.4064)
			(end 0.7874 -0.4064)
			(stroke
				(width 0.1524)
				(type default)
			)
			(layer "F.SilkS")
		)
		(fp_line
			(start 0.7874 -0.4064)
			(end 0.7874 0.4064)
			(stroke
				(width 0.1524)
				(type default)
			)
			(layer "F.SilkS")
		)
		(fp_line
			(start -0.67945 0.3048)
			(end -0.67945 -0.305054)
			(stroke
				(width 0.1)
				(type default)
			)
			(layer "F.Fab")
		)
		(fp_line
			(start -0.12065 0.3048)
			(end -0.67945 0.3048)
			(stroke
				(width 0.1)
				(type default)
			)
			(layer "F.Fab")
		)
		(fp_line
			(start 0.120396 0.3048)
			(end 0.120396 0.2794)
			(stroke
				(width 0.1)
				(type default)
			)
			(layer "F.Fab")
		)
		(fp_line
			(start 0.67945 0.3048)
			(end 0.120396 0.3048)
			(stroke
				(width 0.1)
				(type default)
			)
			(layer "F.Fab")
		)
		(fp_line
			(start -0.12065 0.2794)
			(end -0.12065 0.3048)
			(stroke
				(width 0.1)
				(type default)
			)
			(layer "F.Fab")
		)
		(fp_line
			(start 0.120396 0.2794)
			(end -0.12065 0.2794)
			(stroke
				(width 0.1)
				(type default)
			)
			(layer "F.Fab")
		)
		(fp_line
			(start -0.12065 -0.2794)
			(end 0.12065 -0.2794)
			(stroke
				(width 0.1)
				(type default)
			)
			(layer "F.Fab")
		)
		(fp_line
			(start 0.12065 -0.2794)
			(end 0.12065 -0.3048)
			(stroke
				(width 0.1)
				(type default)
			)
			(layer "F.Fab")
		)
		(fp_line
			(start 0.12065 -0.3048)
			(end 0.67945 -0.3048)
			(stroke
				(width 0.1)
				(type default)
			)
			(layer "F.Fab")
		)
		(fp_line
			(start 0.67945 -0.3048)
			(end 0.67945 0.3048)
			(stroke
				(width 0.1)
				(type default)
			)
			(layer "F.Fab")
		)
		(fp_line
			(start -0.67945 -0.305054)
			(end -0.12065 -0.305054)
			(stroke
				(width 0.1)
				(type default)
			)
			(layer "F.Fab")
		)
		(fp_line
			(start -0.12065 -0.305054)
			(end -0.12065 -0.2794)
			(stroke
				(width 0.1)
				(type default)
			)
			(layer "F.Fab")
		)
		(pad "1" smd circle
			(at -0.40005 0 270)
			(size 0 0)
			(layers "F.Cu" "F.Mask" "F.Paste")
			(net "LED_D21_R2")
		)
		(pad "2" smd circle
			(at 0.40005 0 270)
			(size 0 0)
			(layers "F.Cu" "F.Mask" "F.Paste")
			(net "LED_D21_R1")
		)
	)
	(footprint ""
		(layer "F.Cu")
		(at 66.0146 -66.0146)
		(property "Reference" "R468"
			(at 0 0 0)
			(layer "F.SilkS")
			(hide yes)
			(effects
				(font
					(size 1.27 1.27)
				)
			)
		)
		(property "Value" ""
			(at 0 0 0)
			(layer "F.Fab")
			(effects
				(font
					(size 1.27 1.27)
				)
			)
		)
		(duplicate_pad_numbers_are_jumpers no)
		(fp_line
			(start -0.7874 -0.4064)
			(end 0.7874 -0.4064)
			(stroke
				(width 0.1524)
				(type default)
			)
			(layer "F.SilkS")
		)
		(fp_line
			(start -0.7874 0.4064)
			(end -0.7874 -0.4064)
			(stroke
				(width 0.1524)
				(type default)
			)
			(layer "F.SilkS")
		)
		(fp_line
			(start 0.7874 -0.4064)
			(end 0.7874 0.4064)
			(stroke
				(width 0.1524)
				(type default)
			)
			(layer "F.SilkS")
		)
		(fp_line
			(start 0.7874 0.4064)
			(end -0.7874 0.4064)
			(stroke
				(width 0.1524)
				(type default)
			)
			(layer "F.SilkS")
		)
		(fp_line
			(start -0.67945 -0.305054)
			(end -0.12065 -0.305054)
			(stroke
				(width 0.1)
				(type default)
			)
			(layer "F.Fab")
		)
		(fp_line
			(start -0.67945 0.3048)
			(end -0.67945 -0.305054)
			(stroke
				(width 0.1)
				(type default)
			)
			(layer "F.Fab")
		)
		(fp_line
			(start -0.12065 -0.305054)
			(end -0.12065 -0.2794)
			(stroke
				(width 0.1)
				(type default)
			)
			(layer "F.Fab")
		)
		(fp_line
			(start -0.12065 -0.2794)
			(end 0.12065 -0.2794)
			(stroke
				(width 0.1)
				(type default)
			)
			(layer "F.Fab")
		)
		(fp_line
			(start -0.12065 0.2794)
			(end -0.12065 0.3048)
			(stroke
				(width 0.1)
				(type default)
			)
			(layer "F.Fab")
		)
		(fp_line
			(start -0.12065 0.3048)
			(end -0.67945 0.3048)
			(stroke
				(width 0.1)
				(type default)
			)
			(layer "F.Fab")
		)
		(fp_line
			(start 0.120396 0.2794)
			(end -0.12065 0.2794)
			(stroke
				(width 0.1)
				(type default)
			)
			(layer "F.Fab")
		)
		(fp_line
			(start 0.120396 0.3048)
			(end 0.120396 0.2794)
			(stroke
				(width 0.1)
				(type default)
			)
			(layer "F.Fab")
		)
		(fp_line
			(start 0.12065 -0.3048)
			(end 0.67945 -0.3048)
			(stroke
				(width 0.1)
				(type default)
			)
			(layer "F.Fab")
		)
		(fp_line
			(start 0.12065 -0.2794)
			(end 0.12065 -0.3048)
			(stroke
				(width 0.1)
				(type default)
			)
			(layer "F.Fab")
		)
		(fp_line
			(start 0.67945 -0.3048)
			(end 0.67945 0.3048)
			(stroke
				(width 0.1)
				(type default)
			)
			(layer "F.Fab")
		)
		(fp_line
			(start 0.67945 0.3048)
			(end 0.120396 0.3048)
			(stroke
				(width 0.1)
				(type default)
			)
			(layer "F.Fab")
		)
		(pad "1" smd circle
			(at -0.40005 0)
			(size 0 0)
			(layers "F.Cu" "F.Mask" "F.Paste")
			(net "SPI_BMC_TPM_CLK_R1")
		)
		(pad "2" smd circle
			(at 0.40005 0)
			(size 0 0)
			(layers "F.Cu" "F.Mask" "F.Paste")
			(net "SPI_BMC_TPM_CLK")
		)
	)
)
